FILE_TYPE = MACRO_DRAWING;
SET COLOR_WIRE YELLOW;
SET COLOR_PROP ORANGE;
SET COLOR_DOT WHITE;
SET COLOR_ARC YELLOW;
SET COLOR_BODY GREEN;
SET COLOR_NOTE PURPLE;
SET PROP_DISPLAY VALUE;
SET PAGE_NUMBER P456;
FORCEADD QUANTA_TITLE_BLOCK_C..1
(0 0);
FORCEPROP 1 LAST CUSTOM_TXT_CDS <NAME_2>
J 0
(-3175 50);
FORCEPROP 1 LAST CUSTOM_TXT_CDS <NAME_1>
J 0
(-3175 175);
FORCEPROP 1 LAST CUSTOM_TXT_CDS <Q_NUMBER>
J 0
(-1403 103);
DISPLAY 1.212766 (-1403 103);
FORCEPROP 1 LAST CUSTOM_TXT_CDS <Q_PROJ>
J 0
(-2382 102);
DISPLAY 1.212766 (-2382 102);
FORCEPROP 1 LAST CUSTOM_TXT_CDS <Q_REV>
J 0
(-184 103);
DISPLAY 1.212766 (-184 103);
FORCEPROP 1 LAST CUSTOM_TXT_CDS <CON_LAST_MODIFIED>
J 0
(-1885 15);
DISPLAY 0.978723 (-1885 15);
FORCEPROP 1 LAST CUSTOM_TXT_CDS <CON_PAGE_NUM> OF <CON_TOTAL_PAGES>
J 0
(-446 18);
DISPLAY 0.978723 (-446 18);
FORCEPROP 1 LAST Q_TITLE RETIMER_CPU1_P2(10)
J 0
(-9366 26);
DISPLAY 2.446809 (-9366 26);
PAINT GREEN (-9366 26);
FORCEPROP 2 LAST CDS_LIB pure_quanta
J 0
(0 0);
DISPLAY INVISIBLE (0 0);
FORCEPROP 1 LAST CDS_LMAN_SYM_OUTLINE -9475,6775,100,-125
J 0
(0 0);
DISPLAY 0.468085 (0 0);
PAINT GREEN (0 0);
DISPLAY INVISIBLE (0 0);
FORCEPROP 2 LAST PAGE_BORDER TRUE
J 0
(-7890 5250);
DISPLAY 0.638298 (-7890 5250);
PAINT PINK (-7890 5250);
DISPLAY INVISIBLE (-7890 5250);
FORCEPROP 2 LAST CDS_XR_PAGE_TITLE CR-348 : @T6G_MB_LIB.T6G(SCH_1):PAGE348
J 0
(-7890 5250);
DISPLAY 0.638298 (-7890 5250);
PAINT PINK (-7890 5250);
DISPLAY INVISIBLE (-7890 5250);
FORCEPROP 2 LAST CUSTOM_TXT_CDS <XR_PAGE_TITLE>
J 0
(-7890 5250);
DISPLAY 0.638298 (-7890 5250);
PAINT PINK (-7890 5250);
DISPLAY INVISIBLE (-7890 5250);
FORCEPROP 1 LAST COMMENT_BODY TRUE
J 0
(12 -13);
DISPLAY 0.978723 (12 -13);
PAINT GREEN (12 -13);
DISPLAY INVISIBLE (12 -13);
FORCEPROP 1 LAST Q_DEPT BU9
J 1
(-3763 49);
DISPLAY 1.957447 (-3763 49);
PAINT GREEN (-3763 49);
DISPLAY INVISIBLE (-3763 49);
FORCEPROP 0 LAST CDS_CON_LAST_MODIFIED Thu Aug 24 10:17:04 2023
J 0
(-1885 15);
DISPLAY INVISIBLE (-1885 15);
QUIT
